# TIMECARD (Time Appliance Project (Time Card)) — schematic netlist excerpt (pin names and nets, part order shuffled) for the footprints in the layout excerpt that follows; sources: Cadence DE-HDL packaged netlist, KiCad conversion of R4006-B0001-02_R01.brd

R497  RESISTOR  1MOHM 1%  pkg SMC_0402R_H016  page 23 : \1\ = SG ; \2\ = BF_SMA4_SIG_IO_CONN
DS5  OPTICAL  pkg SMC_DS_063X031_V4  page 26 : A = UNNAMED_14_OPTICAL_I143_A ; C = SG

(kicad_pcb
	(version 20260206)
	(generator "pcbnew")
	(generator_version "10.0")
	(general
		(thickness 1.6)
		(legacy_teardrops no)
	)
	(paper "A4")
	(title_block
		(title "timecard-production-celestica-r4006 — R4006-B0001-02_R01.brd")
		(comment 1 "Time Appliance Project (Time Card) / footprints 525-526 of 1113")
	)
	(layers
		(0 "F.Cu" signal "TOP")
		(4 "In1.Cu" signal "L02_GND1")
		(6 "In2.Cu" signal "L03_SIG1")
		(8 "In3.Cu" signal "L04_GND2")
		(10 "In4.Cu" signal "L05_VCC1")
		(12 "In5.Cu" signal "L06_VCC2")
		(14 "In6.Cu" signal "L07_GND3")
		(16 "In7.Cu" signal "L08_SIG2")
		(18 "In8.Cu" signal "L09_GND4")
		(2 "B.Cu" signal "BOTTOM")
		(9 "F.Adhes" user "F.Adhesive")
		(11 "B.Adhes" user "B.Adhesive")
		(13 "F.Paste" user "Package Geometry/Pastemask Top")
		(15 "B.Paste" user "Package Geometry/Pastemask Bottom")
		(5 "F.SilkS" user "Ref Des/Silkscreen Top")
		(7 "B.SilkS" user "Ref Des/Silkscreen Bottom")
		(1 "F.Mask" user "Board Geometry/Soldermask Top")
		(3 "B.Mask" user "Board Geometry/Soldermask Bottom")
		(17 "Dwgs.User" user "User.Drawings")
		(19 "Cmts.User" user "User.Comments")
		(21 "Eco1.User" user "User.Eco1")
		(23 "Eco2.User" user "User.Eco2")
		(25 "Edge.Cuts" user "Board Geometry/Outline")
		(27 "Margin" user)
		(31 "F.CrtYd" user "Package Geometry/Place Bound Top")
		(29 "B.CrtYd" user "Package Geometry/Place Bound Bottom")
		(35 "F.Fab" user "Ref Des/Assembly Top")
		(33 "B.Fab" user "Ref Des/Assembly Bottom")
	)
	(footprint ""
		(layer "F.Cu")
		(at 11.2522 -16.9672 -90)
		(property "Reference" "R497"
			(at -0.0508 1.05283 90)
			(unlocked yes)
			(layer "F.SilkS")
			(effects
				(font
					(size 0.7874 0.5842)
					(thickness 0.1524)
				)
			)
		)
		(property "Value" "VAL*"
			(at 0.02032 2.13233 270)
			(unlocked yes)
			(layer "F.Fab")
			(hide yes)
			(effects
				(font
					(size 0.7874 0.5842)
					(thickness 0.1524)
				)
			)
		)
		(property "Tolerance" "TOL*"
			(at 0.044704 3.05435 270)
			(unlocked yes)
			(layer "Cmts.User")
			(hide yes)
			(effects
				(font
					(size 0.7874 0.5842)
					(thickness 0.1524)
				)
			)
		)
		(property "User Part Number" "PARTNUM*"
			(at 0.02032 4.024884 270)
			(unlocked yes)
			(layer "Cmts.User")
			(hide yes)
			(effects
				(font
					(size 0.7874 0.5842)
					(thickness 0.1524)
				)
			)
		)
		(property "Device Type" "RESISTOR-G155-11004-01,1MOHM,1%"
			(at 0.008382 1.210564 270)
			(unlocked yes)
			(layer "F.Fab")
			(hide yes)
			(effects
				(font
					(size 0.7874 0.5842)
					(thickness 0.1524)
				)
			)
		)
		(duplicate_pad_numbers_are_jumpers no)
		(fp_line
			(start -1.143 0.5588)
			(end 1.143 0.5588)
			(stroke
				(width 0.1)
				(type default)
			)
			(layer "F.SilkS")
		)
		(fp_line
			(start 1.143 0.5588)
			(end 1.143 -0.5588)
			(stroke
				(width 0.1)
				(type default)
			)
			(layer "F.SilkS")
		)
		(fp_line
			(start -1.143 -0.5588)
			(end -1.143 0.5588)
			(stroke
				(width 0.1)
				(type default)
			)
			(layer "F.SilkS")
		)
		(fp_line
			(start 1.143 -0.5588)
			(end -1.143 -0.5588)
			(stroke
				(width 0.1)
				(type default)
			)
			(layer "F.SilkS")
		)
		(fp_poly
			(pts
				(xy -1.143 0.5588) (xy 1.143 0.5588) (xy 1.143 -0.5588) (xy -1.143 -0.5588)
			)
			(stroke
				(width 0)
				(type default)
			)
			(fill no)
			(layer "F.CrtYd")
		)
		(fp_line
			(start -0.508 0.3048)
			(end 0.508 0.3048)
			(stroke
				(width 0.1)
				(type default)
			)
			(layer "F.Fab")
		)
		(fp_line
			(start 0.508 0.3048)
			(end 0.508 -0.3048)
			(stroke
				(width 0.1)
				(type default)
			)
			(layer "F.Fab")
		)
		(fp_line
			(start -0.508 -0.3048)
			(end -0.508 0.3048)
			(stroke
				(width 0.1)
				(type default)
			)
			(layer "F.Fab")
		)
		(fp_line
			(start 0.508 -0.3048)
			(end -0.508 -0.3048)
			(stroke
				(width 0.1)
				(type default)
			)
			(layer "F.Fab")
		)
		(pad "1" smd rect
			(at -0.5334 0 270)
			(size 0.7112 0.6096)
			(layers "F.Cu" "F.Mask" "F.Paste")
			(net "SG")
		)
		(pad "2" smd rect
			(at 0.5334 0 270)
			(size 0.7112 0.6096)
			(layers "F.Cu" "F.Mask" "F.Paste")
			(net "BF_SMA4_SIG_IO_CONN")
		)
		(zone
			(layer "F.Cu")
			(hatch none 0.5)
			(connect_pads
				(clearance 0)
			)
			(min_thickness 0.25)
			(keepout
				(tracks allowed)
				(vias not_allowed)
				(pads allowed)
				(copperpour not_allowed)
				(footprints allowed)
			)
			(placement
				(enabled no)
				(sheetname "")
			)
			(fill
				(thermal_gap 0.5)
				(thermal_bridge_width 0.5)
				(island_removal_mode 0)
			)
			(polygon
				(pts
					(xy 10.9474 -17.0434) (xy 10.9474 -16.891) (xy 11.557 -16.891) (xy 11.557 -17.0434)
				)
			)
		)
		(zone
			(layer "F.Cu")
			(hatch none 0.5)
			(connect_pads
				(clearance 0)
			)
			(min_thickness 0.25)
			(keepout
				(tracks not_allowed)
				(vias allowed)
				(pads allowed)
				(copperpour not_allowed)
				(footprints allowed)
			)
			(placement
				(enabled no)
				(sheetname "")
			)
			(fill
				(thermal_gap 0.5)
				(thermal_bridge_width 0.5)
				(island_removal_mode 0)
			)
			(polygon
				(pts
					(xy 10.9474 -17.0434) (xy 10.9474 -16.891) (xy 11.557 -16.891) (xy 11.557 -17.0434)
				)
			)
		)
	)
	(footprint ""
		(layer "F.Cu")
		(at 147.049998 -104.350058 -90)
		(property "Reference" "DS5"
			(at 0.464058 -1.452372 90)
			(unlocked yes)
			(layer "F.SilkS")
			(effects
				(font
					(size 0.7874 0.5842)
					(thickness 0.1524)
				)
			)
		)
		(property "Value" ""
			(at 0 0 270)
			(layer "F.Fab")
			(effects
				(font
					(size 1.27 1.27)
				)
			)
		)
		(property "Device Type" "OPTICAL-G170-10143-01"
			(at 0.1778 1.483081 270)
			(unlocked yes)
			(layer "F.Fab")
			(hide yes)
			(effects
				(font
					(size 0.786892 0.583946)
					(thickness 0.000001)
				)
			)
		)
		(property "User Part Number" "PARTNUM*"
			(at 0.1778 2.422881 270)
			(unlocked yes)
			(layer "Cmts.User")
			(hide yes)
			(effects
				(font
					(size 0.786892 0.583946)
					(thickness 0.000001)
				)
			)
		)
		(duplicate_pad_numbers_are_jumpers no)
		(fp_line
			(start -0.9398 1.3462)
			(end -2.2098 1.3462)
			(stroke
				(width 0.1)
				(type default)
			)
			(layer "F.SilkS")
		)
		(fp_line
			(start -1.5748 0.7112)
			(end -1.5748 1.9812)
			(stroke
				(width 0.1)
				(type default)
			)
			(layer "F.SilkS")
		)
		(fp_line
			(start -1.397508 0.704088)
			(end -1.397508 -0.704088)
			(stroke
				(width 0.1)
				(type default)
			)
			(layer "F.SilkS")
		)
		(fp_line
			(start 1.397508 0.704088)
			(end -1.397508 0.704088)
			(stroke
				(width 0.1)
				(type default)
			)
			(layer "F.SilkS")
		)
		(fp_line
			(start -1.397508 -0.704088)
			(end 1.397508 -0.704088)
			(stroke
				(width 0.1)
				(type default)
			)
			(layer "F.SilkS")
		)
		(fp_line
			(start 1.397508 -0.704088)
			(end 1.397508 0.704088)
			(stroke
				(width 0.1)
				(type default)
			)
			(layer "F.SilkS")
		)
		(fp_rect
			(start 1.905508 0.704088)
			(end 1.397508 -0.704088)
			(stroke
				(width 0)
				(type default)
			)
			(fill yes)
			(layer "F.SilkS")
		)
		(fp_rect
			(start 1.905508 0.958088)
			(end -1.651508 -0.958088)
			(stroke
				(width 0)
				(type default)
			)
			(fill no)
			(layer "F.CrtYd")
		)
		(fp_line
			(start -0.9398 0.9652)
			(end -2.2098 0.9652)
			(stroke
				(width 0.1)
				(type default)
			)
			(layer "F.Fab")
		)
		(fp_line
			(start -0.850138 0.450088)
			(end 0.850138 0.450088)
			(stroke
				(width 0.1)
				(type default)
			)
			(layer "F.Fab")
		)
		(fp_line
			(start 0.850138 0.450088)
			(end 0.850138 -0.450088)
			(stroke
				(width 0.1)
				(type default)
			)
			(layer "F.Fab")
		)
		(fp_line
			(start -1.5748 0.3302)
			(end -1.5748 1.6002)
			(stroke
				(width 0.1)
				(type default)
			)
			(layer "F.Fab")
		)
		(fp_line
			(start -0.850138 -0.450088)
			(end -0.850138 0.450088)
			(stroke
				(width 0.1)
				(type default)
			)
			(layer "F.Fab")
		)
		(fp_line
			(start 0.850138 -0.450088)
			(end -0.850138 -0.450088)
			(stroke
				(width 0.1)
				(type default)
			)
			(layer "F.Fab")
		)
		(fp_rect
			(start 0.850138 0.450088)
			(end 0.342138 -0.450088)
			(stroke
				(width 0)
				(type default)
			)
			(fill yes)
			(layer "F.Fab")
		)
		(fp_text user "C"
			(at 2.400808 -0.397002 0)
			(unlocked yes)
			(layer "F.SilkS")
			(effects
				(font
					(size 0.635 0.4064)
					(thickness 0.1524)
				)
			)
		)
		(fp_text user "A"
			(at -1.536192 -1.286002 0)
			(unlocked yes)
			(layer "F.SilkS")
			(effects
				(font
					(size 0.635 0.4064)
					(thickness 0.1524)
				)
			)
		)
		(fp_text user "C"
			(at 1.80467 0.0762 0)
			(unlocked yes)
			(layer "F.Fab")
			(effects
				(font
					(size 0.7874 0.5842)
					(thickness 0.1524)
				)
			)
		)
		(fp_text user "A"
			(at -1.528572 -0.651002 0)
			(unlocked yes)
			(layer "F.Fab")
			(effects
				(font
					(size 0.7874 0.5842)
					(thickness 0.1524)
				)
			)
		)
		(pad "A" smd rect
			(at -0.749808 0 270)
			(size 0.7874 0.7874)
			(layers "F.Cu" "F.Mask" "F.Paste")
			(net "UNNAMED_14_OPTICAL_I143_A")
		)
		(pad "C" smd rect
			(at 0.749808 0 270)
			(size 0.7874 0.7874)
			(layers "F.Cu" "F.Mask" "F.Paste")
			(net "SG")
		)
	)
)
